(kicad_pcb
	(version 20260206)
	(generator "pcbnew")
	(generator_version "10.0")
	(general
		(thickness 1.21888)
		(legacy_teardrops no)
	)
	(paper "A4")
	(title_block
		(title "timecard-proto-v0 — Timingcard_PCB.PcbDoc")
		(comment 1 "Time Appliance Project (Time Card) / footprints 124-134 of 167")
	)
	(layers
		(0 "F.Cu" signal "TOP")
		(4 "In1.Cu" signal "SGND")
		(6 "In2.Cu" signal "IN1")
		(8 "In3.Cu" signal "IN2")
		(10 "In4.Cu" signal "SGND1")
		(2 "B.Cu" signal "BOTTOM")
		(9 "F.Adhes" user "F.Adhesive")
		(11 "B.Adhes" user "B.Adhesive")
		(13 "F.Paste" user "Top Paste")
		(15 "B.Paste" user "Bottom Paste")
		(5 "F.SilkS" user "Top Overlay")
		(7 "B.SilkS" user "Bottom Overlay")
		(1 "F.Mask" user "Top Solder")
		(3 "B.Mask" user "Bottom Solder")
		(17 "Dwgs.User" user "User.Drawings")
		(19 "Cmts.User" user "User.Comments")
		(21 "Eco1.User" user "User.Eco1")
		(23 "Eco2.User" user "User.Eco2")
		(25 "Edge.Cuts" user)
		(27 "Margin" user)
		(31 "F.CrtYd" user "Top Courtyard")
		(29 "B.CrtYd" user "Bottom Courtyard")
		(35 "F.Fab" user "Top Component Center")
		(33 "B.Fab" user "Bottom Component Center")
	)
	(footprint "IntegratedCircuits:SOP64P600X170-16N"
		(layer "F.Cu")
		(at 102.655195 56.1322)
		(property "Reference" "U16"
			(at -4.161335 2.19029 90)
			(unlocked yes)
			(layer "F.SilkS")
			(effects
				(font
					(size 0.762 0.762)
					(thickness 0.2286)
				)
				(justify left bottom)
			)
		)
		(property "Value" "FT230XS-R"
			(at -3.4671 5.25399 0)
			(unlocked yes)
			(layer "F.SilkS")
			(hide yes)
			(effects
				(font
					(size 1.524 1.524)
					(thickness 0.254)
				)
				(justify left bottom)
			)
		)
		(sheetname "GPS_IMU_SENSORS")
		(sheetfile "GPS_IMU_SENSORS.kicad_sch")
		(duplicate_pad_numbers_are_jumpers no)
		(fp_line
			(start -1.6 -2.5)
			(end 1.6 -2.5)
			(stroke
				(width 0.2)
				(type solid)
			)
			(layer "F.SilkS")
		)
		(fp_line
			(start -1.6 2.5)
			(end -1.6 -2.5)
			(stroke
				(width 0.2)
				(type solid)
			)
			(layer "F.SilkS")
		)
		(fp_line
			(start -1.6 2.5)
			(end 1.6 2.5)
			(stroke
				(width 0.2)
				(type solid)
			)
			(layer "F.SilkS")
		)
		(fp_line
			(start 1.6 2.5)
			(end 1.6 -2.5)
			(stroke
				(width 0.2)
				(type solid)
			)
			(layer "F.SilkS")
		)
		(fp_circle
			(center -2.725 -2.9975)
			(end -2.725 -3.1225)
			(stroke
				(width 0.25)
				(type solid)
			)
			(fill no)
			(layer "F.SilkS")
		)
		(fp_circle
			(center -0.6 -1.5)
			(end -0.6 -1.8)
			(stroke
				(width 0.6)
				(type solid)
			)
			(fill no)
			(layer "F.SilkS")
		)
		(pad "1" smd oval
			(at -2.725 -2.2225 90)
			(size 0.45 1.45)
			(layers "F.Cu" "F.Mask" "F.Paste")
			(net "NetJP2_2")
		)
		(pad "2" smd oval
			(at -2.725 -1.5875 90)
			(size 0.45 1.45)
			(layers "F.Cu" "F.Mask" "F.Paste")
		)
		(pad "3" smd oval
			(at -2.725 -0.9525 90)
			(size 0.45 1.45)
			(layers "F.Cu" "F.Mask" "F.Paste")
			(net "NetU16_3")
		)
		(pad "4" smd oval
			(at -2.725 -0.3175 90)
			(size 0.45 1.45)
			(layers "F.Cu" "F.Mask" "F.Paste")
			(net "NetJP1_2")
		)
		(pad "5" smd oval
			(at -2.725 0.3175 90)
			(size 0.45 1.45)
			(layers "F.Cu" "F.Mask" "F.Paste")
			(net "GND")
		)
		(pad "6" smd oval
			(at -2.725 0.9525 90)
			(size 0.45 1.45)
			(layers "F.Cu" "F.Mask" "F.Paste")
		)
		(pad "7" smd oval
			(at -2.725 1.5875 90)
			(size 0.45 1.45)
			(layers "F.Cu" "F.Mask" "F.Paste")
		)
		(pad "8" smd oval
			(at -2.725 2.2225 90)
			(size 0.45 1.45)
			(layers "F.Cu" "F.Mask" "F.Paste")
			(net "NetJ4_3")
		)
		(pad "9" smd oval
			(at 2.725 2.2225 90)
			(size 0.45 1.45)
			(layers "F.Cu" "F.Mask" "F.Paste")
			(net "NetJ4_2")
		)
		(pad "10" smd oval
			(at 2.725 1.5875 90)
			(size 0.45 1.45)
			(layers "F.Cu" "F.Mask" "F.Paste")
			(net "NetU16_3")
		)
		(pad "11" smd oval
			(at 2.725 0.9525 90)
			(size 0.45 1.45)
			(layers "F.Cu" "F.Mask" "F.Paste")
			(net "NetR43_2")
		)
		(pad "12" smd oval
			(at 2.725 0.3175 90)
			(size 0.45 1.45)
			(layers "F.Cu" "F.Mask" "F.Paste")
			(net "+5.0V")
		)
		(pad "13" smd oval
			(at 2.725 -0.3175 90)
			(size 0.45 1.45)
			(layers "F.Cu" "F.Mask" "F.Paste")
			(net "GND")
		)
		(pad "14" smd oval
			(at 2.725 -0.9525 90)
			(size 0.45 1.45)
			(layers "F.Cu" "F.Mask" "F.Paste")
		)
		(pad "15" smd oval
			(at 2.725 -1.5875 90)
			(size 0.45 1.45)
			(layers "F.Cu" "F.Mask" "F.Paste")
		)
		(pad "16" smd oval
			(at 2.725 -2.2225 90)
			(size 0.45 1.45)
			(layers "F.Cu" "F.Mask" "F.Paste")
		)
	)
	(footprint "Passives:IND_PM124SH"
		(layer "F.Cu")
		(at 228.156595 94.2576 -90)
		(property "Reference" "L2"
			(at -7.488745 -4.73741 0)
			(unlocked yes)
			(layer "F.SilkS")
			(effects
				(font
					(size 0.762 0.762)
					(thickness 0.2286)
				)
				(justify left bottom)
			)
		)
		(property "Value" "PM124SH-100M-RC"
			(at 11.14679 12.7381 0)
			(unlocked yes)
			(layer "F.SilkS")
			(hide yes)
			(effects
				(font
					(size 1.524 1.524)
					(thickness 0.254)
				)
				(justify left bottom)
			)
		)
		(sheetname "POWER")
		(sheetfile "POWER.kicad_sch")
		(duplicate_pad_numbers_are_jumpers no)
		(fp_line
			(start -6.681 6.4)
			(end -6.681 -6.4)
			(stroke
				(width 0.254)
				(type solid)
			)
			(layer "F.SilkS")
		)
		(fp_line
			(start 6.681 6.4)
			(end -6.681 6.4)
			(stroke
				(width 0.254)
				(type solid)
			)
			(layer "F.SilkS")
		)
		(fp_line
			(start 6.681 6.4)
			(end 6.681 -6.4)
			(stroke
				(width 0.254)
				(type solid)
			)
			(layer "F.SilkS")
		)
		(fp_line
			(start 6.681 -6.4)
			(end -6.681 -6.4)
			(stroke
				(width 0.254)
				(type solid)
			)
			(layer "F.SilkS")
		)
		(pad "1" smd rect
			(at -4.85 0 270)
			(size 2.9 5.4)
			(layers "F.Cu" "F.Mask" "F.Paste")
			(net "+3.3V")
		)
		(pad "2" smd rect
			(at 4.85 0 270)
			(size 2.9 5.4)
			(layers "F.Cu" "F.Mask" "F.Paste")
			(net "NetC3_2")
		)
	)
	(footprint "Capacitors:CAPC2012X14N"
		(layer "F.Cu")
		(at 217.888595 87.9786 90)
		(property "Reference" "C7"
			(at 3 0.393345 90)
			(unlocked yes)
			(layer "F.SilkS")
			(effects
				(font
					(size 0.762 0.762)
					(thickness 0.2286)
				)
				(justify left bottom)
			)
		)
		(property "Value" "CAP_0805_10UF_25V"
			(at -15.71879 10.0965 0)
			(unlocked yes)
			(layer "F.SilkS")
			(hide yes)
			(effects
				(font
					(size 1.524 1.524)
					(thickness 0.254)
				)
				(justify left bottom)
			)
		)
		(sheetname "POWER")
		(sheetfile "POWER.kicad_sch")
		(duplicate_pad_numbers_are_jumpers no)
		(fp_line
			(start -0.762 -0.9652)
			(end 0.762 -0.9652)
			(stroke
				(width 0.1524)
				(type solid)
			)
			(layer "F.SilkS")
		)
		(fp_line
			(start -0.762 0.9652)
			(end 0.762 0.9652)
			(stroke
				(width 0.1524)
				(type solid)
			)
			(layer "F.SilkS")
		)
		(pad "1" smd rect
			(at -0.9 0 180)
			(size 1.45 1.15)
			(layers "F.Cu" "F.Mask" "F.Paste")
			(net "+3.3V")
		)
		(pad "2" smd rect
			(at 0.9 0 180)
			(size 1.45 1.15)
			(layers "F.Cu" "F.Mask" "F.Paste")
			(net "GND")
		)
	)
	(footprint "Miscellaneous:SM8"
		(layer "F.Cu")
		(at 232.093595 78.5096)
		(property "Reference" "X1"
			(at 2.97205 -3.221545 0)
			(unlocked yes)
			(layer "F.SilkS")
			(effects
				(font
					(size 0.762 0.762)
					(thickness 0.2286)
				)
				(justify left bottom)
			)
		)
		(property "Value" "MC306"
			(at -3.5941 7.59079 0)
			(unlocked yes)
			(layer "F.SilkS")
			(hide yes)
			(effects
				(font
					(size 1.524 1.524)
					(thickness 0.254)
				)
				(justify left bottom)
			)
		)
		(sheetname "GPS_IMU_SENSORS")
		(sheetfile "GPS_IMU_SENSORS.kicad_sch")
		(duplicate_pad_numbers_are_jumpers no)
		(fp_line
			(start -4.445 -1.905)
			(end -4.064 -1.905)
			(stroke
				(width 0.1524)
				(type solid)
			)
			(layer "F.SilkS")
		)
		(fp_line
			(start -4.445 1.905)
			(end -4.445 -1.905)
			(stroke
				(width 0.1524)
				(type solid)
			)
			(layer "F.SilkS")
		)
		(fp_line
			(start -4.445 1.905)
			(end -4.064 1.905)
			(stroke
				(width 0.1524)
				(type solid)
			)
			(layer "F.SilkS")
		)
		(fp_line
			(start -3.81 1.27)
			(end -3.81 -1.27)
			(stroke
				(width 0.1524)
				(type solid)
			)
			(layer "F.SilkS")
		)
		(fp_line
			(start -1.397 -1.905)
			(end 1.397 -1.905)
			(stroke
				(width 0.1524)
				(type solid)
			)
			(layer "F.SilkS")
		)
		(fp_line
			(start -1.397 1.905)
			(end 1.397 1.905)
			(stroke
				(width 0.1524)
				(type solid)
			)
			(layer "F.SilkS")
		)
		(fp_line
			(start 4.064 -1.905)
			(end 4.445 -1.905)
			(stroke
				(width 0.1524)
				(type solid)
			)
			(layer "F.SilkS")
		)
		(fp_line
			(start 4.064 1.905)
			(end 4.445 1.905)
			(stroke
				(width 0.1524)
				(type solid)
			)
			(layer "F.SilkS")
		)
		(fp_line
			(start 4.445 -1.651)
			(end 4.445 -1.905)
			(stroke
				(width 0.1524)
				(type solid)
			)
			(layer "F.SilkS")
		)
		(fp_line
			(start 4.445 1.651)
			(end 4.445 -1.651)
			(stroke
				(width 0.1524)
				(type solid)
			)
			(layer "F.SilkS")
		)
		(fp_line
			(start 4.445 1.905)
			(end 4.445 1.651)
			(stroke
				(width 0.1524)
				(type solid)
			)
			(layer "F.SilkS")
		)
		(fp_circle
			(center -4.064 2.54)
			(end -4.064 2.413)
			(stroke
				(width 0.254)
				(type solid)
			)
			(fill no)
			(layer "F.SilkS")
		)
		(pad "1" smd rect
			(at -2.75 1.6 90)
			(size 1.9 1.3)
			(layers "F.Cu" "F.Mask" "F.Paste")
			(net "NetC85_2")
		)
		(pad "2" smd rect
			(at 2.75 1.6 90)
			(size 1.9 1.3)
			(layers "F.Cu" "F.Mask" "F.Paste")
		)
		(pad "3" smd rect
			(at 2.75 -1.6 90)
			(size 1.9 1.3)
			(layers "F.Cu" "F.Mask" "F.Paste")
		)
		(pad "4" smd rect
			(at -2.75 -1.6 90)
			(size 1.9 1.3)
			(layers "F.Cu" "F.Mask" "F.Paste")
			(net "NetC86_2")
		)
	)
	(footprint "Passives:INDC1608X09N"
		(layer "F.Cu")
		(at 163.894595 89.0506 90)
		(property "Reference" "FB3"
			(at 1.80389 0.715465 90)
			(unlocked yes)
			(layer "F.SilkS")
			(effects
				(font
					(size 0.762 0.762)
					(thickness 0.2286)
				)
				(justify left bottom)
			)
		)
		(property "Value" "MPZ1608_220OHM_0603"
			(at -3.88239 -0.5461 0)
			(unlocked yes)
			(layer "F.SilkS")
			(hide yes)
			(effects
				(font
					(size 1.524 1.524)
					(thickness 0.254)
				)
				(justify left bottom)
			)
		)
		(sheetname "MAC")
		(sheetfile "MAC.kicad_sch")
		(duplicate_pad_numbers_are_jumpers no)
		(pad "1" smd rect
			(at -0.665 0 180)
			(size 0.98 0.87)
			(layers "F.Cu" "F.Mask" "F.Paste")
			(net "NetC72_2")
		)
		(pad "2" smd rect
			(at 0.665 0 180)
			(size 0.98 0.87)
			(layers "F.Cu" "F.Mask" "F.Paste")
			(net "+3.3V_CLEAN")
		)
	)
	(footprint "Vault:CAPC1608X87X45ML20T05"
		(layer "F.Cu")
		(at 165.672595 82.8276 -90)
		(property "Reference" "C79"
			(at -3.224 1.665655 90)
			(unlocked yes)
			(layer "F.SilkS")
			(effects
				(font
					(size 0.762 0.762)
					(thickness 0.2286)
				)
				(justify left bottom)
			)
		)
		(property "Value" "0.1uF"
			(at 3.47599 0.2921 0)
			(unlocked yes)
			(layer "F.SilkS")
			(hide yes)
			(effects
				(font
					(size 1.524 1.524)
					(thickness 0.254)
				)
				(justify left bottom)
			)
		)
		(sheetname "MAC")
		(sheetfile "MAC.kicad_sch")
		(duplicate_pad_numbers_are_jumpers no)
		(pad "1" smd rect
			(at -0.7 0)
			(size 1.1 1.05)
			(layers "F.Cu" "F.Mask" "F.Paste")
			(net "GND")
		)
		(pad "2" smd rect
			(at 0.7 0)
			(size 1.1 1.05)
			(layers "F.Cu" "F.Mask" "F.Paste")
			(net "+3.3V_CLEAN")
		)
	)
	(footprint "Vault:CAPC1608X87X45ML20T05"
		(layer "F.Cu")
		(at 227.648595 118.1336)
		(property "Reference" "C16"
			(at 1.74 0.638345 0)
			(unlocked yes)
			(layer "F.SilkS")
			(effects
				(font
					(size 0.762 0.762)
					(thickness 0.2286)
				)
				(justify left bottom)
			)
		)
		(property "Value" "0.1uF"
			(at 0.3429 7.15899 0)
			(unlocked yes)
			(layer "F.SilkS")
			(hide yes)
			(effects
				(font
					(size 1.524 1.524)
					(thickness 0.254)
				)
				(justify left bottom)
			)
		)
		(sheetname "POWER")
		(sheetfile "POWER.kicad_sch")
		(duplicate_pad_numbers_are_jumpers no)
		(pad "1" smd rect
			(at -0.7 0 90)
			(size 1.1 1.05)
			(layers "F.Cu" "F.Mask" "F.Paste")
			(net "GND")
		)
		(pad "2" smd rect
			(at 0.7 0 90)
			(size 1.1 1.05)
			(layers "F.Cu" "F.Mask" "F.Paste")
			(net "+5.0V")
		)
	)
	(footprint "Resistors:RESC1608X50N"
		(layer "F.Cu")
		(at 176.988595 55.1786 180)
		(property "Reference" "R35"
			(at -1.7 -0.393345 0)
			(unlocked yes)
			(layer "F.SilkS")
			(effects
				(font
					(size 0.762 0.762)
					(thickness 0.2286)
				)
				(justify left bottom)
			)
		)
		(property "Value" "ERJ-3EKF1001V"
			(at 0.4445 -3.72999 0)
			(unlocked yes)
			(layer "F.SilkS")
			(hide yes)
			(effects
				(font
					(size 1.524 1.524)
					(thickness 0.254)
				)
				(justify left bottom)
			)
		)
		(sheetname "USER_IO")
		(sheetfile "USER_IO.kicad_sch")
		(duplicate_pad_numbers_are_jumpers no)
		(fp_line
			(start 0 -0.5)
			(end 0 0.5)
			(stroke
				(width 0.1524)
				(type solid)
			)
			(layer "F.SilkS")
		)
		(pad "1" smd rect
			(at -0.69 0 270)
			(size 1 0.72)
			(layers "F.Cu" "F.Mask" "F.Paste")
			(net "KEY1")
		)
		(pad "2" smd rect
			(at 0.69 0 270)
			(size 1 0.72)
			(layers "F.Cu" "F.Mask" "F.Paste")
			(net "NetR33_1")
		)
	)
	(footprint "Capacitors:CAPC2012X14N"
		(layer "F.Cu")
		(at 166.307595 78.1286)
		(property "Reference" "C84"
			(at -1.6256 -1.684655 0)
			(unlocked yes)
			(layer "F.SilkS")
			(effects
				(font
					(size 0.762 0.762)
					(thickness 0.2286)
				)
				(justify left bottom)
			)
		)
		(property "Value" "CAP_0805_1UF_50V"
			(at -1.5875 3.52679 0)
			(unlocked yes)
			(layer "F.SilkS")
			(hide yes)
			(effects
				(font
					(size 1.524 1.524)
					(thickness 0.254)
				)
				(justify left bottom)
			)
		)
		(sheetname "MAC")
		(sheetfile "MAC.kicad_sch")
		(duplicate_pad_numbers_are_jumpers no)
		(fp_line
			(start -0.762 -0.9652)
			(end 0.762 -0.9652)
			(stroke
				(width 0.1524)
				(type solid)
			)
			(layer "F.SilkS")
		)
		(fp_line
			(start -0.762 0.9652)
			(end 0.762 0.9652)
			(stroke
				(width 0.1524)
				(type solid)
			)
			(layer "F.SilkS")
		)
		(pad "1" smd rect
			(at -0.9 0 90)
			(size 1.45 1.15)
			(layers "F.Cu" "F.Mask" "F.Paste")
			(net "GND")
		)
		(pad "2" smd rect
			(at 0.9 0 90)
			(size 1.45 1.15)
			(layers "F.Cu" "F.Mask" "F.Paste")
			(net "+3.3V_CLEAN")
		)
	)
	(footprint "Miscellaneous:SiT5155"
		(layer "F.Cu")
		(at 147.003595 85.0882)
		(property "Reference" "U13"
			(at 2.63571 2.950655 0)
			(unlocked yes)
			(layer "F.SilkS")
			(effects
				(font
					(size 0.762 0.762)
					(thickness 0.2286)
				)
				(justify left bottom)
			)
		)
		(property "Value" "SiT5356AI-FQA33-IT-10.000000"
			(at -2.37473 5.60959 0)
			(unlocked yes)
			(layer "F.SilkS")
			(hide yes)
			(effects
				(font
					(size 1.524 1.524)
					(thickness 0.254)
				)
				(justify left bottom)
			)
		)
		(sheetname "MAC")
		(sheetfile "MAC.kicad_sch")
		(duplicate_pad_numbers_are_jumpers no)
		(fp_line
			(start -2.032 -3.048)
			(end -0.66154 -3.048)
			(stroke
				(width 0.2032)
				(type solid)
			)
			(layer "F.SilkS")
		)
		(fp_line
			(start -2.032 -1.45426)
			(end -2.032 -3.048)
			(stroke
				(width 0.2032)
				(type solid)
			)
			(layer "F.SilkS")
		)
		(fp_line
			(start -2.032 3.048)
			(end -2.032 2.54)
			(stroke
				(width 0.2032)
				(type solid)
			)
			(layer "F.SilkS")
		)
		(fp_line
			(start -2.032 3.048)
			(end -1.524 3.048)
			(stroke
				(width 0.2032)
				(type solid)
			)
			(layer "F.SilkS")
		)
		(fp_line
			(start 1.524 -3.048)
			(end 2.032 -3.048)
			(stroke
				(width 0.2032)
				(type solid)
			)
			(layer "F.SilkS")
		)
		(fp_line
			(start 1.524 3.048)
			(end 2.032 3.048)
			(stroke
				(width 0.2032)
				(type solid)
			)
			(layer "F.SilkS")
		)
		(fp_line
			(start 2.032 -2.54)
			(end 2.032 -3.048)
			(stroke
				(width 0.2032)
				(type solid)
			)
			(layer "F.SilkS")
		)
		(fp_line
			(start 2.032 3.048)
			(end 2.032 2.54)
			(stroke
				(width 0.2032)
				(type solid)
			)
			(layer "F.SilkS")
		)
		(pad "1" smd rect
			(at -1.175 -2.025)
			(size 1.05 1.15)
			(layers "F.Cu" "F.Mask" "F.Paste")
			(net "OE_5356")
		)
		(pad "2" smd rect
			(at -1.025 -0.6)
			(size 1.35 0.7)
			(layers "F.Cu" "F.Mask" "F.Paste")
			(net "SCL")
		)
		(pad "3" smd rect
			(at -1.025 0.6)
			(size 1.35 0.7)
			(layers "F.Cu" "F.Mask" "F.Paste")
		)
		(pad "4" smd rect
			(at -1.175 2.025)
			(size 1.05 1.15)
			(layers "F.Cu" "F.Mask" "F.Paste")
			(net "GND")
		)
		(pad "5" smd rect
			(at 0 2.025 90)
			(size 1.15 0.7)
			(layers "F.Cu" "F.Mask" "F.Paste")
			(net "NetR42_1")
		)
		(pad "6" smd rect
			(at 1.175 2.025)
			(size 1.05 1.15)
			(layers "F.Cu" "F.Mask" "F.Paste")
			(net "DCXO1")
		)
		(pad "7" smd rect
			(at 1.025 0.6)
			(size 1.35 0.7)
			(layers "F.Cu" "F.Mask" "F.Paste")
		)
		(pad "8" smd rect
			(at 1.025 -0.6)
			(size 1.35 0.7)
			(layers "F.Cu" "F.Mask" "F.Paste")
		)
		(pad "9" smd rect
			(at 1.175 -2.025)
			(size 1.05 1.15)
			(layers "F.Cu" "F.Mask" "F.Paste")
			(net "+3.3V_CLEAN")
		)
		(pad "10" smd rect
			(at 0 -2.025 90)
			(size 1.15 0.7)
			(layers "F.Cu" "F.Mask" "F.Paste")
			(net "SDA")
		)
	)
	(footprint "Capacitors:CAPC2012X14N"
		(layer "F.Cu")
		(at 222.949595 82.5736 180)
		(property "Reference" "C56"
			(at 4.261 -0.498345 0)
			(unlocked yes)
			(layer "F.SilkS")
			(effects
				(font
					(size 0.762 0.762)
					(thickness 0.2286)
				)
				(justify left bottom)
			)
		)
		(property "Value" "CAP_0805_10UF_25V"
			(at -15.9385 4.09321 0)
			(unlocked yes)
			(layer "F.SilkS")
			(hide yes)
			(effects
				(font
					(size 1.524 1.524)
					(thickness 0.254)
				)
				(justify left bottom)
			)
		)
		(sheetname "GPS_IMU_SENSORS")
		(sheetfile "GPS_IMU_SENSORS.kicad_sch")
		(duplicate_pad_numbers_are_jumpers no)
		(fp_line
			(start 0.762 0.9652)
			(end -0.762 0.9652)
			(stroke
				(width 0.1524)
				(type solid)
			)
			(layer "F.SilkS")
		)
		(fp_line
			(start 0.762 -0.9652)
			(end -0.762 -0.9652)
			(stroke
				(width 0.1524)
				(type solid)
			)
			(layer "F.SilkS")
		)
		(pad "1" smd rect
			(at -0.9 0 270)
			(size 1.45 1.15)
			(layers "F.Cu" "F.Mask" "F.Paste")
			(net "+3.3V")
		)
		(pad "2" smd rect
			(at 0.9 0 270)
			(size 1.45 1.15)
			(layers "F.Cu" "F.Mask" "F.Paste")
			(net "GND")
		)
	)
)
